# T6G (Grand Teton) — schematic netlist excerpt (pin names and nets, part order shuffled) for the footprints in the layout excerpt that follows; sources: Cadence DE-HDL packaged netlist, KiCad conversion of 04192023_DAF0TMB3IC0_F0TG_MB_C_brd_V02_OCP.brd

PC2217  Q_CAP  0.1UF 25V 10% X7R  pkg 0402  page 146 : A = P12V_E1S_0 ; B = GND
R3864  Q_RES  0 5% EMPTY  pkg 0402LF  page 257 : A = P12V_OCP_SFF_ISENSE_MPS_MAM ; B = P12V_OCP_SFF_ISENSE_MAM

(kicad_pcb
	(version 20260206)
	(generator "pcbnew")
	(generator_version "10.0")
	(general
		(thickness 1.6)
		(legacy_teardrops no)
	)
	(paper "A4")
	(title_block
		(title "04192023_DAF0TMB3IC0_F0TG_MB_C_brd_V02_OCP.brd")
		(comment 1 "Grand Teton / footprints 1148-1149 of 8354")
	)
	(layers
		(0 "F.Cu" signal "TOP")
		(4 "In1.Cu" signal "GND")
		(6 "In2.Cu" signal "IN1")
		(8 "In3.Cu" signal "GND1")
		(10 "In4.Cu" signal "IN2")
		(12 "In5.Cu" signal "GND2")
		(14 "In6.Cu" signal "IN3")
		(16 "In7.Cu" signal "GND3")
		(18 "In8.Cu" signal "VCC")
		(20 "In9.Cu" signal "VCC1")
		(22 "In10.Cu" signal "GND4")
		(24 "In11.Cu" signal "IN4")
		(26 "In12.Cu" signal "GND5")
		(28 "In13.Cu" signal "IN5")
		(30 "In14.Cu" signal "GND6")
		(32 "In15.Cu" signal "IN6")
		(34 "In16.Cu" signal "GND7")
		(2 "B.Cu" signal "BOTTOM")
		(9 "F.Adhes" user "F.Adhesive")
		(11 "B.Adhes" user "B.Adhesive")
		(13 "F.Paste" user "Package Geometry/Pastemask Top")
		(15 "B.Paste" user "Package Geometry/Pastemask Bottom")
		(5 "F.SilkS" user "Ref Des/Silkscreen Top")
		(7 "B.SilkS" user "Ref Des/Silkscreen Bottom")
		(1 "F.Mask" user "Board Geometry/Soldermask Top")
		(3 "B.Mask" user "Board Geometry/Soldermask Bottom")
		(17 "Dwgs.User" user "User.Drawings")
		(19 "Cmts.User" user "User.Comments")
		(21 "Eco1.User" user "User.Eco1")
		(23 "Eco2.User" user "User.Eco2")
		(25 "Edge.Cuts" user "Board Geometry/Outline")
		(27 "Margin" user)
		(31 "F.CrtYd" user "Package Geometry/Place Bound Top")
		(29 "B.CrtYd" user "Package Geometry/Place Bound Bottom")
		(35 "F.Fab" user "Ref Des/Assembly Top")
		(33 "B.Fab" user "Ref Des/Assembly Bottom")
	)
	(footprint ""
		(layer "F.Cu")
		(at 249.713496 -48.094138)
		(property "Reference" "PC2217"
			(at 0 0 0)
			(layer "F.SilkS")
			(hide yes)
			(effects
				(font
					(size 1.27 1.27)
				)
			)
		)
		(property "Value" ""
			(at 0 0 0)
			(layer "F.Fab")
			(effects
				(font
					(size 1.27 1.27)
				)
			)
		)
		(duplicate_pad_numbers_are_jumpers no)
		(fp_line
			(start -0.7874 -0.4064)
			(end 0.7874 -0.4064)
			(stroke
				(width 0.1524)
				(type default)
			)
			(layer "F.SilkS")
		)
		(fp_line
			(start -0.7874 0.4064)
			(end -0.7874 -0.4064)
			(stroke
				(width 0.1524)
				(type default)
			)
			(layer "F.SilkS")
		)
		(fp_line
			(start 0.7874 -0.4064)
			(end 0.7874 0.4064)
			(stroke
				(width 0.1524)
				(type default)
			)
			(layer "F.SilkS")
		)
		(fp_line
			(start 0.7874 0.4064)
			(end -0.7874 0.4064)
			(stroke
				(width 0.1524)
				(type default)
			)
			(layer "F.SilkS")
		)
		(fp_line
			(start -0.67945 -0.305054)
			(end -0.12065 -0.305054)
			(stroke
				(width 0.1)
				(type default)
			)
			(layer "F.Fab")
		)
		(fp_line
			(start -0.67945 0.3048)
			(end -0.67945 -0.305054)
			(stroke
				(width 0.1)
				(type default)
			)
			(layer "F.Fab")
		)
		(fp_line
			(start -0.12065 -0.305054)
			(end -0.12065 -0.2794)
			(stroke
				(width 0.1)
				(type default)
			)
			(layer "F.Fab")
		)
		(fp_line
			(start -0.12065 -0.2794)
			(end 0.12065 -0.2794)
			(stroke
				(width 0.1)
				(type default)
			)
			(layer "F.Fab")
		)
		(fp_line
			(start -0.12065 0.2794)
			(end -0.12065 0.3048)
			(stroke
				(width 0.1)
				(type default)
			)
			(layer "F.Fab")
		)
		(fp_line
			(start -0.12065 0.3048)
			(end -0.67945 0.3048)
			(stroke
				(width 0.1)
				(type default)
			)
			(layer "F.Fab")
		)
		(fp_line
			(start 0.120396 0.2794)
			(end -0.12065 0.2794)
			(stroke
				(width 0.1)
				(type default)
			)
			(layer "F.Fab")
		)
		(fp_line
			(start 0.120396 0.3048)
			(end 0.120396 0.2794)
			(stroke
				(width 0.1)
				(type default)
			)
			(layer "F.Fab")
		)
		(fp_line
			(start 0.12065 -0.3048)
			(end 0.67945 -0.3048)
			(stroke
				(width 0.1)
				(type default)
			)
			(layer "F.Fab")
		)
		(fp_line
			(start 0.12065 -0.2794)
			(end 0.12065 -0.3048)
			(stroke
				(width 0.1)
				(type default)
			)
			(layer "F.Fab")
		)
		(fp_line
			(start 0.67945 -0.3048)
			(end 0.67945 0.3048)
			(stroke
				(width 0.1)
				(type default)
			)
			(layer "F.Fab")
		)
		(fp_line
			(start 0.67945 0.3048)
			(end 0.120396 0.3048)
			(stroke
				(width 0.1)
				(type default)
			)
			(layer "F.Fab")
		)
		(pad "1" smd circle
			(at -0.40005 0)
			(size 0 0)
			(layers "F.Cu" "F.Mask" "F.Paste")
			(net "P12V_E1S_0")
		)
		(pad "2" smd circle
			(at 0.40005 0)
			(size 0 0)
			(layers "F.Cu" "F.Mask" "F.Paste")
			(net "GND")
		)
	)
	(footprint ""
		(layer "F.Cu")
		(at 312.342022 -33.715706 180)
		(property "Reference" "R3864"
			(at 0 0 180)
			(layer "F.SilkS")
			(hide yes)
			(effects
				(font
					(size 1.27 1.27)
				)
			)
		)
		(property "Value" ""
			(at 0 0 180)
			(layer "F.Fab")
			(effects
				(font
					(size 1.27 1.27)
				)
			)
		)
		(duplicate_pad_numbers_are_jumpers no)
		(fp_line
			(start 0.7874 0.4064)
			(end -0.7874 0.4064)
			(stroke
				(width 0.1524)
				(type default)
			)
			(layer "F.SilkS")
		)
		(fp_line
			(start 0.7874 -0.4064)
			(end 0.7874 0.4064)
			(stroke
				(width 0.1524)
				(type default)
			)
			(layer "F.SilkS")
		)
		(fp_line
			(start -0.7874 0.4064)
			(end -0.7874 -0.4064)
			(stroke
				(width 0.1524)
				(type default)
			)
			(layer "F.SilkS")
		)
		(fp_line
			(start -0.7874 -0.4064)
			(end 0.7874 -0.4064)
			(stroke
				(width 0.1524)
				(type default)
			)
			(layer "F.SilkS")
		)
		(fp_line
			(start 0.67945 0.3048)
			(end 0.120396 0.3048)
			(stroke
				(width 0.1)
				(type default)
			)
			(layer "F.Fab")
		)
		(fp_line
			(start 0.67945 -0.3048)
			(end 0.67945 0.3048)
			(stroke
				(width 0.1)
				(type default)
			)
			(layer "F.Fab")
		)
		(fp_line
			(start 0.12065 -0.2794)
			(end 0.12065 -0.3048)
			(stroke
				(width 0.1)
				(type default)
			)
			(layer "F.Fab")
		)
		(fp_line
			(start 0.12065 -0.3048)
			(end 0.67945 -0.3048)
			(stroke
				(width 0.1)
				(type default)
			)
			(layer "F.Fab")
		)
		(fp_line
			(start 0.120396 0.3048)
			(end 0.120396 0.2794)
			(stroke
				(width 0.1)
				(type default)
			)
			(layer "F.Fab")
		)
		(fp_line
			(start 0.120396 0.2794)
			(end -0.12065 0.2794)
			(stroke
				(width 0.1)
				(type default)
			)
			(layer "F.Fab")
		)
		(fp_line
			(start -0.12065 0.3048)
			(end -0.67945 0.3048)
			(stroke
				(width 0.1)
				(type default)
			)
			(layer "F.Fab")
		)
		(fp_line
			(start -0.12065 0.2794)
			(end -0.12065 0.3048)
			(stroke
				(width 0.1)
				(type default)
			)
			(layer "F.Fab")
		)
		(fp_line
			(start -0.12065 -0.2794)
			(end 0.12065 -0.2794)
			(stroke
				(width 0.1)
				(type default)
			)
			(layer "F.Fab")
		)
		(fp_line
			(start -0.12065 -0.305054)
			(end -0.12065 -0.2794)
			(stroke
				(width 0.1)
				(type default)
			)
			(layer "F.Fab")
		)
		(fp_line
			(start -0.67945 0.3048)
			(end -0.67945 -0.305054)
			(stroke
				(width 0.1)
				(type default)
			)
			(layer "F.Fab")
		)
		(fp_line
			(start -0.67945 -0.305054)
			(end -0.12065 -0.305054)
			(stroke
				(width 0.1)
				(type default)
			)
			(layer "F.Fab")
		)
		(pad "1" smd rect
			(at -0.40005 0)
			(size 0.4572 0.508)
			(layers "F.Cu" "F.Mask" "F.Paste")
			(net "P12V_OCP_SFF_ISENSE_MPS_MAM")
		)
		(pad "2" smd rect
			(at 0.40005 0)
			(size 0.4572 0.508)
			(layers "F.Cu" "F.Mask" "F.Paste")
			(net "P12V_OCP_SFF_ISENSE_MAM")
		)
	)
)
